(kicad_pcb
	(version 20260206)
	(generator "pcbnew")
	(generator_version "10.0")
	(general
		(thickness 1.6)
		(legacy_teardrops no)
	)
	(paper "A4")
	(title_block
		(title "peb — Lightning_PEB_BRD.brd")
		(comment 1 "Lightning (Wiwynn / Facebook NVMe JBOF) / footprints 762-769 of 2563")
	)
	(layers
		(0 "F.Cu" signal "TOP")
		(4 "In1.Cu" signal "L2GND")
		(6 "In2.Cu" signal "L3")
		(8 "In3.Cu" signal "L4VCC")
		(10 "In4.Cu" signal "L5VCC")
		(12 "In5.Cu" signal "L6")
		(14 "In6.Cu" signal "L7GND")
		(2 "B.Cu" signal "BOTTOM")
		(9 "F.Adhes" user "F.Adhesive")
		(11 "B.Adhes" user "B.Adhesive")
		(13 "F.Paste" user "Package Geometry/Pastemask Top")
		(15 "B.Paste" user "Package Geometry/Pastemask Bottom")
		(5 "F.SilkS" user "Ref Des/Silkscreen Top")
		(7 "B.SilkS" user "Ref Des/Silkscreen Bottom")
		(1 "F.Mask" user "Board Geometry/Soldermask Top")
		(3 "B.Mask" user "Board Geometry/Soldermask Bottom")
		(17 "Dwgs.User" user "User.Drawings")
		(19 "Cmts.User" user "User.Comments")
		(21 "Eco1.User" user "User.Eco1")
		(23 "Eco2.User" user "User.Eco2")
		(25 "Edge.Cuts" user "Board Geometry/Outline")
		(27 "Margin" user)
		(31 "F.CrtYd" user "Package Geometry/Place Bound Top")
		(29 "B.CrtYd" user "Package Geometry/Place Bound Bottom")
		(35 "F.Fab" user "Ref Des/Assembly Top")
		(33 "B.Fab" user "Ref Des/Assembly Bottom")
	)
	(footprint ""
		(layer "F.Cu")
		(at 273.843496 -8.903716 -90)
		(property "Reference" "R2901"
			(at 0 0 270)
			(layer "F.SilkS")
			(hide yes)
			(effects
				(font
					(size 1.27 1.27)
				)
			)
		)
		(property "Value" "0R2J-2-GP"
			(at 0.064008 -3.993896 270)
			(unlocked yes)
			(layer "F.Fab")
			(hide yes)
			(effects
				(font
					(size 1.016 1.016)
					(thickness 0.1524)
				)
			)
		)
		(property "Device Type" "R402H16"
			(at 0.064008 -5.517896 270)
			(unlocked yes)
			(layer "F.Fab")
			(hide yes)
			(effects
				(font
					(size 1.016 1.016)
					(thickness 0.1524)
				)
			)
		)
		(duplicate_pad_numbers_are_jumpers no)
		(fp_line
			(start -0.508 -0.9398)
			(end -0.508 0.9398)
			(stroke
				(width 0.1524)
				(type default)
			)
			(layer "F.SilkS")
		)
		(fp_line
			(start 0.508 -0.9398)
			(end -0.508 -0.9398)
			(stroke
				(width 0.1524)
				(type default)
			)
			(layer "F.SilkS")
		)
		(fp_rect
			(start -0.508 0.9398)
			(end 0.508 -0.9398)
			(stroke
				(width 0)
				(type default)
			)
			(fill no)
			(layer "F.CrtYd")
		)
		(fp_rect
			(start -0.508 0.9398)
			(end 0.508 -0.9398)
			(stroke
				(width 0)
				(type default)
			)
			(fill no)
			(layer "F.Fab")
		)
		(pad "1" smd custom
			(at 0 -0.4445 270)
			(size 0.1397 0.1397)
			(layers "F.Cu" "F.Mask" "F.Paste")
			(net "BMC_I2C11_MINI5_SDA")
			(options
				(clearance outline)
				(anchor circle)
			)
			(primitives
				(gr_poly
					(pts
						(arc
							(start -0.1778 -0.2794)
							(mid -0.249642 -0.249642)
							(end -0.2794 -0.1778)
						)
						(arc
							(start -0.2794 0.1778)
							(mid -0.249642 0.249642)
							(end -0.1778 0.2794)
						)
						(arc
							(start 0.1778 0.2794)
							(mid 0.249642 0.249642)
							(end 0.2794 0.1778)
						)
						(arc
							(start 0.2794 -0.1778)
							(mid 0.249642 -0.249642)
							(end 0.1778 -0.2794)
						)
					)
					(width 0)
					(fill yes)
				)
			)
		)
		(pad "2" smd custom
			(at 0 0.4445 270)
			(size 0.1397 0.1397)
			(layers "F.Cu" "F.Mask" "F.Paste")
			(net "8644_SDA_R_5")
			(options
				(clearance outline)
				(anchor circle)
			)
			(primitives
				(gr_poly
					(pts
						(arc
							(start -0.1778 -0.2794)
							(mid -0.249642 -0.249642)
							(end -0.2794 -0.1778)
						)
						(arc
							(start -0.2794 0.1778)
							(mid -0.249642 0.249642)
							(end -0.1778 0.2794)
						)
						(arc
							(start 0.1778 0.2794)
							(mid 0.249642 0.249642)
							(end 0.2794 0.1778)
						)
						(arc
							(start 0.2794 -0.1778)
							(mid 0.249642 -0.249642)
							(end 0.1778 -0.2794)
						)
					)
					(width 0)
					(fill yes)
				)
			)
		)
	)
	(footprint ""
		(layer "F.Cu")
		(at 53.721 -118.11 -90)
		(property "Reference" "R460"
			(at 0 0 270)
			(layer "F.SilkS")
			(hide yes)
			(effects
				(font
					(size 1.27 1.27)
				)
			)
		)
		(property "Value" "0R2J-2-GP"
			(at 0.064008 -3.993896 270)
			(unlocked yes)
			(layer "F.Fab")
			(hide yes)
			(effects
				(font
					(size 1.016 1.016)
					(thickness 0.1524)
				)
			)
		)
		(property "Device Type" "R402H16"
			(at 0.064008 -5.517896 270)
			(unlocked yes)
			(layer "F.Fab")
			(hide yes)
			(effects
				(font
					(size 1.016 1.016)
					(thickness 0.1524)
				)
			)
		)
		(duplicate_pad_numbers_are_jumpers no)
		(fp_line
			(start -0.508 -0.9398)
			(end -0.508 0.9398)
			(stroke
				(width 0.1524)
				(type default)
			)
			(layer "F.SilkS")
		)
		(fp_line
			(start 0.508 -0.9398)
			(end -0.508 -0.9398)
			(stroke
				(width 0.1524)
				(type default)
			)
			(layer "F.SilkS")
		)
		(fp_rect
			(start -0.508 0.9398)
			(end 0.508 -0.9398)
			(stroke
				(width 0)
				(type default)
			)
			(fill no)
			(layer "F.CrtYd")
		)
		(fp_rect
			(start -0.508 0.9398)
			(end 0.508 -0.9398)
			(stroke
				(width 0)
				(type default)
			)
			(fill no)
			(layer "F.Fab")
		)
		(pad "1" smd custom
			(at 0 -0.4445 270)
			(size 0.1397 0.1397)
			(layers "F.Cu" "F.Mask" "F.Paste")
			(net "BMC_I2C7_B_DPB_SDA")
			(options
				(clearance outline)
				(anchor circle)
			)
			(primitives
				(gr_poly
					(pts
						(arc
							(start -0.1778 -0.2794)
							(mid -0.249642 -0.249642)
							(end -0.2794 -0.1778)
						)
						(arc
							(start -0.2794 0.1778)
							(mid -0.249642 0.249642)
							(end -0.1778 0.2794)
						)
						(arc
							(start 0.1778 0.2794)
							(mid 0.249642 0.249642)
							(end 0.2794 0.1778)
						)
						(arc
							(start 0.2794 -0.1778)
							(mid 0.249642 -0.249642)
							(end 0.1778 -0.2794)
						)
					)
					(width 0)
					(fill yes)
				)
			)
		)
		(pad "2" smd custom
			(at 0 0.4445 270)
			(size 0.1397 0.1397)
			(layers "F.Cu" "F.Mask" "F.Paste")
			(net "BMC0_SMB7_DAT")
			(options
				(clearance outline)
				(anchor circle)
			)
			(primitives
				(gr_poly
					(pts
						(arc
							(start -0.1778 -0.2794)
							(mid -0.249642 -0.249642)
							(end -0.2794 -0.1778)
						)
						(arc
							(start -0.2794 0.1778)
							(mid -0.249642 0.249642)
							(end -0.1778 0.2794)
						)
						(arc
							(start 0.1778 0.2794)
							(mid 0.249642 0.249642)
							(end 0.2794 0.1778)
						)
						(arc
							(start 0.2794 -0.1778)
							(mid 0.249642 -0.249642)
							(end 0.1778 -0.2794)
						)
					)
					(width 0)
					(fill yes)
				)
			)
		)
	)
	(footprint ""
		(layer "F.Cu")
		(at 52.578 -178.816 90)
		(property "Reference" "C710"
			(at 0 0 90)
			(layer "F.SilkS")
			(hide yes)
			(effects
				(font
					(size 1.27 1.27)
				)
			)
		)
		(property "Value" "SC220P50V3JN-GP"
			(at 0 -2.8194 90)
			(unlocked yes)
			(layer "F.Fab")
			(hide yes)
			(effects
				(font
					(size 1.016 1.016)
					(thickness 0.1524)
				)
			)
		)
		(property "Device Type" "C603H36"
			(at 0 -4.3434 90)
			(unlocked yes)
			(layer "F.Fab")
			(hide yes)
			(effects
				(font
					(size 1.016 1.016)
					(thickness 0.1524)
				)
			)
		)
		(duplicate_pad_numbers_are_jumpers no)
		(fp_line
			(start 0.508 0)
			(end -0.508 0)
			(stroke
				(width 0.2032)
				(type default)
			)
			(layer "F.SilkS")
		)
		(fp_rect
			(start -0.5842 1.3335)
			(end 0.5842 -1.3335)
			(stroke
				(width 0)
				(type default)
			)
			(fill no)
			(layer "F.CrtYd")
		)
		(fp_rect
			(start -0.5842 1.3335)
			(end 0.5842 -1.3335)
			(stroke
				(width 0)
				(type default)
			)
			(fill no)
			(layer "F.Fab")
		)
		(pad "1" smd custom
			(at 0 -0.762 90)
			(size 0.2159 0.2159)
			(layers "F.Cu" "F.Mask" "F.Paste")
			(net "BMC_I2C8_CLKBUF1_SCL_R")
			(options
				(clearance outline)
				(anchor circle)
			)
			(primitives
				(gr_poly
					(pts
						(arc
							(start -0.3302 -0.4318)
							(mid -0.402042 -0.402042)
							(end -0.4318 -0.3302)
						)
						(arc
							(start -0.4318 0.3302)
							(mid -0.402042 0.402042)
							(end -0.3302 0.4318)
						)
						(arc
							(start 0.3302 0.4318)
							(mid 0.402042 0.402042)
							(end 0.4318 0.3302)
						)
						(arc
							(start 0.4318 -0.3302)
							(mid 0.402042 -0.402042)
							(end 0.3302 -0.4318)
						)
					)
					(width 0)
					(fill yes)
				)
			)
		)
		(pad "2" smd custom
			(at 0 0.762 90)
			(size 0.2159 0.2159)
			(layers "F.Cu" "F.Mask" "F.Paste")
			(net "GND")
			(options
				(clearance outline)
				(anchor circle)
			)
			(primitives
				(gr_poly
					(pts
						(arc
							(start -0.3302 -0.4318)
							(mid -0.402042 -0.402042)
							(end -0.4318 -0.3302)
						)
						(arc
							(start -0.4318 0.3302)
							(mid -0.402042 0.402042)
							(end -0.3302 0.4318)
						)
						(arc
							(start 0.3302 0.4318)
							(mid 0.402042 0.402042)
							(end 0.4318 0.3302)
						)
						(arc
							(start 0.4318 -0.3302)
							(mid 0.402042 -0.402042)
							(end 0.3302 -0.4318)
						)
					)
					(width 0)
					(fill yes)
				)
			)
		)
	)
	(footprint ""
		(layer "F.Cu")
		(at 173.808136 -212.420454 180)
		(property "Reference" "C139"
			(at 0 0 180)
			(layer "F.SilkS")
			(hide yes)
			(effects
				(font
					(size 1.27 1.27)
				)
			)
		)
		(property "Value" "SCD22U10V2KX-1GP"
			(at 1.1811 -2.7051 180)
			(unlocked yes)
			(layer "F.Fab")
			(hide yes)
			(effects
				(font
					(size 1.016 1.016)
					(thickness 0.1524)
				)
			)
		)
		(property "Device Type" "C402H22"
			(at 1.1811 -4.2291 180)
			(unlocked yes)
			(layer "F.Fab")
			(hide yes)
			(effects
				(font
					(size 1.016 1.016)
					(thickness 0.1524)
				)
			)
		)
		(duplicate_pad_numbers_are_jumpers no)
		(fp_rect
			(start -0.4318 0.9525)
			(end 0.4318 -0.9525)
			(stroke
				(width 0)
				(type default)
			)
			(fill no)
			(layer "F.CrtYd")
		)
		(fp_rect
			(start -0.4318 0.9525)
			(end 0.4318 -0.9525)
			(stroke
				(width 0)
				(type default)
			)
			(fill no)
			(layer "F.Fab")
		)
		(pad "1" smd custom
			(at 0 -0.4445 180)
			(size 0.1524 0.1524)
			(layers "F.Cu" "F.Mask" "F.Paste")
			(net "PCIE_TX_CAP_N49")
			(options
				(clearance outline)
				(anchor circle)
			)
			(primitives
				(gr_poly
					(pts
						(arc
							(start 0.3048 -0.2032)
							(mid 0.275042 -0.275042)
							(end 0.2032 -0.3048)
						)
						(arc
							(start -0.2032 -0.3048)
							(mid -0.275042 -0.275042)
							(end -0.3048 -0.2032)
						)
						(arc
							(start -0.3048 0.2032)
							(mid -0.275042 0.275042)
							(end -0.2032 0.3048)
						)
						(arc
							(start 0.2032 0.3048)
							(mid 0.275042 0.275042)
							(end 0.3048 0.2032)
						)
					)
					(width 0)
					(fill yes)
				)
			)
		)
		(pad "2" smd custom
			(at 0 0.4445 180)
			(size 0.1524 0.1524)
			(layers "F.Cu" "F.Mask" "F.Paste")
			(net "PCIE_TX_N49")
			(options
				(clearance outline)
				(anchor circle)
			)
			(primitives
				(gr_poly
					(pts
						(arc
							(start 0.3048 -0.2032)
							(mid 0.275042 -0.275042)
							(end 0.2032 -0.3048)
						)
						(arc
							(start -0.2032 -0.3048)
							(mid -0.275042 -0.275042)
							(end -0.3048 -0.2032)
						)
						(arc
							(start -0.3048 0.2032)
							(mid -0.275042 0.275042)
							(end -0.2032 0.3048)
						)
						(arc
							(start 0.2032 0.3048)
							(mid 0.275042 0.275042)
							(end 0.3048 0.2032)
						)
					)
					(width 0)
					(fill yes)
				)
			)
		)
	)
	(footprint ""
		(layer "F.Cu")
		(at 229.108 -23.241 180)
		(property "Reference" "R3718"
			(at 0 0 180)
			(layer "F.SilkS")
			(hide yes)
			(effects
				(font
					(size 1.27 1.27)
				)
			)
		)
		(property "Value" "4K7R2F-GP"
			(at 0.064008 -3.993896 180)
			(unlocked yes)
			(layer "F.Fab")
			(hide yes)
			(effects
				(font
					(size 1.016 1.016)
					(thickness 0.1524)
				)
			)
		)
		(property "Device Type" "R402H16"
			(at 0.064008 -5.517896 180)
			(unlocked yes)
			(layer "F.Fab")
			(hide yes)
			(effects
				(font
					(size 1.016 1.016)
					(thickness 0.1524)
				)
			)
		)
		(duplicate_pad_numbers_are_jumpers no)
		(fp_line
			(start 0.508 -0.9398)
			(end -0.508 -0.9398)
			(stroke
				(width 0.1524)
				(type default)
			)
			(layer "F.SilkS")
		)
		(fp_line
			(start -0.508 -0.9398)
			(end -0.508 0.9398)
			(stroke
				(width 0.1524)
				(type default)
			)
			(layer "F.SilkS")
		)
		(fp_rect
			(start -0.508 0.9398)
			(end 0.508 -0.9398)
			(stroke
				(width 0)
				(type default)
			)
			(fill no)
			(layer "F.CrtYd")
		)
		(fp_rect
			(start -0.508 0.9398)
			(end 0.508 -0.9398)
			(stroke
				(width 0)
				(type default)
			)
			(fill no)
			(layer "F.Fab")
		)
		(pad "1" smd custom
			(at 0 -0.4445 180)
			(size 0.1397 0.1397)
			(layers "F.Cu" "F.Mask" "F.Paste")
			(net "HOST2_RST_N_LS")
			(options
				(clearance outline)
				(anchor circle)
			)
			(primitives
				(gr_poly
					(pts
						(arc
							(start -0.1778 -0.2794)
							(mid -0.249642 -0.249642)
							(end -0.2794 -0.1778)
						)
						(arc
							(start -0.2794 0.1778)
							(mid -0.249642 0.249642)
							(end -0.1778 0.2794)
						)
						(arc
							(start 0.1778 0.2794)
							(mid 0.249642 0.249642)
							(end 0.2794 0.1778)
						)
						(arc
							(start 0.2794 -0.1778)
							(mid 0.249642 -0.249642)
							(end 0.1778 -0.2794)
						)
					)
					(width 0)
					(fill yes)
				)
			)
		)
		(pad "2" smd custom
			(at 0 0.4445 180)
			(size 0.1397 0.1397)
			(layers "F.Cu" "F.Mask" "F.Paste")
			(net "GND")
			(options
				(clearance outline)
				(anchor circle)
			)
			(primitives
				(gr_poly
					(pts
						(arc
							(start -0.1778 -0.2794)
							(mid -0.249642 -0.249642)
							(end -0.2794 -0.1778)
						)
						(arc
							(start -0.2794 0.1778)
							(mid -0.249642 0.249642)
							(end -0.1778 0.2794)
						)
						(arc
							(start 0.1778 0.2794)
							(mid 0.249642 0.249642)
							(end 0.2794 0.1778)
						)
						(arc
							(start 0.2794 -0.1778)
							(mid 0.249642 -0.249642)
							(end 0.1778 -0.2794)
						)
					)
					(width 0)
					(fill yes)
				)
			)
		)
	)
	(footprint ""
		(layer "F.Cu")
		(at 158.540704 -33.528)
		(property "Reference" "C398"
			(at 0 0 0)
			(layer "F.SilkS")
			(hide yes)
			(effects
				(font
					(size 1.27 1.27)
				)
			)
		)
		(property "Value" "SCD22U10V2KX-1GP"
			(at 1.1811 -2.7051 0)
			(unlocked yes)
			(layer "F.Fab")
			(hide yes)
			(effects
				(font
					(size 1.016 1.016)
					(thickness 0.1524)
				)
			)
		)
		(property "Device Type" "C402H22"
			(at 1.1811 -4.2291 0)
			(unlocked yes)
			(layer "F.Fab")
			(hide yes)
			(effects
				(font
					(size 1.016 1.016)
					(thickness 0.1524)
				)
			)
		)
		(duplicate_pad_numbers_are_jumpers no)
		(fp_rect
			(start -0.4318 0.9525)
			(end 0.4318 -0.9525)
			(stroke
				(width 0)
				(type default)
			)
			(fill no)
			(layer "F.CrtYd")
		)
		(fp_rect
			(start -0.4318 0.9525)
			(end 0.4318 -0.9525)
			(stroke
				(width 0)
				(type default)
			)
			(fill no)
			(layer "F.Fab")
		)
		(pad "1" smd custom
			(at 0 -0.4445)
			(size 0.1524 0.1524)
			(layers "F.Cu" "F.Mask" "F.Paste")
			(net "PCIE_TX_CAP_P89")
			(options
				(clearance outline)
				(anchor circle)
			)
			(primitives
				(gr_poly
					(pts
						(arc
							(start 0.3048 -0.2032)
							(mid 0.275042 -0.275042)
							(end 0.2032 -0.3048)
						)
						(arc
							(start -0.2032 -0.3048)
							(mid -0.275042 -0.275042)
							(end -0.3048 -0.2032)
						)
						(arc
							(start -0.3048 0.2032)
							(mid -0.275042 0.275042)
							(end -0.2032 0.3048)
						)
						(arc
							(start 0.2032 0.3048)
							(mid 0.275042 0.275042)
							(end 0.3048 0.2032)
						)
					)
					(width 0)
					(fill yes)
				)
			)
		)
		(pad "2" smd custom
			(at 0 0.4445)
			(size 0.1524 0.1524)
			(layers "F.Cu" "F.Mask" "F.Paste")
			(net "PCIE_TX_P89")
			(options
				(clearance outline)
				(anchor circle)
			)
			(primitives
				(gr_poly
					(pts
						(arc
							(start 0.3048 -0.2032)
							(mid 0.275042 -0.275042)
							(end 0.2032 -0.3048)
						)
						(arc
							(start -0.2032 -0.3048)
							(mid -0.275042 -0.275042)
							(end -0.3048 -0.2032)
						)
						(arc
							(start -0.3048 0.2032)
							(mid -0.275042 0.275042)
							(end -0.2032 0.3048)
						)
						(arc
							(start 0.2032 0.3048)
							(mid 0.275042 0.275042)
							(end 0.3048 0.2032)
						)
					)
					(width 0)
					(fill yes)
				)
			)
		)
	)
	(footprint ""
		(layer "F.Cu")
		(at 75.795124 -183.235092)
		(property "Reference" "R7928"
			(at 0 0 0)
			(layer "F.SilkS")
			(hide yes)
			(effects
				(font
					(size 1.27 1.27)
				)
			)
		)
		(property "Value" "0R2J-2-GP"
			(at 0.064008 -3.993896 0)
			(unlocked yes)
			(layer "F.Fab")
			(hide yes)
			(effects
				(font
					(size 1.016 1.016)
					(thickness 0.1524)
				)
			)
		)
		(property "Device Type" "R402H16"
			(at 0.064008 -5.517896 0)
			(unlocked yes)
			(layer "F.Fab")
			(hide yes)
			(effects
				(font
					(size 1.016 1.016)
					(thickness 0.1524)
				)
			)
		)
		(duplicate_pad_numbers_are_jumpers no)
		(fp_line
			(start -0.508 -0.9398)
			(end -0.508 0.9398)
			(stroke
				(width 0.1524)
				(type default)
			)
			(layer "F.SilkS")
		)
		(fp_line
			(start 0.508 -0.9398)
			(end -0.508 -0.9398)
			(stroke
				(width 0.1524)
				(type default)
			)
			(layer "F.SilkS")
		)
		(fp_rect
			(start -0.508 0.9398)
			(end 0.508 -0.9398)
			(stroke
				(width 0)
				(type default)
			)
			(fill no)
			(layer "F.CrtYd")
		)
		(fp_rect
			(start -0.508 0.9398)
			(end 0.508 -0.9398)
			(stroke
				(width 0)
				(type default)
			)
			(fill no)
			(layer "F.Fab")
		)
		(pad "1" smd custom
			(at 0 -0.4445)
			(size 0.1397 0.1397)
			(layers "F.Cu" "F.Mask" "F.Paste")
			(net "SSD_PRSNT#5")
			(options
				(clearance outline)
				(anchor circle)
			)
			(primitives
				(gr_poly
					(pts
						(arc
							(start -0.1778 -0.2794)
							(mid -0.249642 -0.249642)
							(end -0.2794 -0.1778)
						)
						(arc
							(start -0.2794 0.1778)
							(mid -0.249642 0.249642)
							(end -0.1778 0.2794)
						)
						(arc
							(start 0.1778 0.2794)
							(mid 0.249642 0.249642)
							(end 0.2794 0.1778)
						)
						(arc
							(start 0.2794 -0.1778)
							(mid 0.249642 -0.249642)
							(end 0.1778 -0.2794)
						)
					)
					(width 0)
					(fill yes)
				)
			)
		)
		(pad "2" smd custom
			(at 0 0.4445)
			(size 0.1397 0.1397)
			(layers "F.Cu" "F.Mask" "F.Paste")
			(net "SSD_PRSNT#5_R")
			(options
				(clearance outline)
				(anchor circle)
			)
			(primitives
				(gr_poly
					(pts
						(arc
							(start -0.1778 -0.2794)
							(mid -0.249642 -0.249642)
							(end -0.2794 -0.1778)
						)
						(arc
							(start -0.2794 0.1778)
							(mid -0.249642 0.249642)
							(end -0.1778 0.2794)
						)
						(arc
							(start 0.1778 0.2794)
							(mid 0.249642 0.249642)
							(end 0.2794 0.1778)
						)
						(arc
							(start 0.2794 -0.1778)
							(mid 0.249642 -0.249642)
							(end 0.1778 -0.2794)
						)
					)
					(width 0)
					(fill yes)
				)
			)
		)
	)
	(footprint ""
		(layer "F.Cu")
		(at 31.623 -51.689 -90)
		(property "Reference" "TC11"
			(at 0 0 270)
			(layer "F.SilkS")
			(hide yes)
			(effects
				(font
					(size 1.27 1.27)
				)
			)
		)
		(property "Value" "SC10U16V5KX-1-GP"
			(at -0.0762 -6.1214 270)
			(unlocked yes)
			(layer "F.Fab")
			(hide yes)
			(effects
				(font
					(size 1.016 1.016)
					(thickness 0.1524)
				)
			)
		)
		(property "Device Type" "C805H54"
			(at -0.0762 -8.1534 270)
			(unlocked yes)
			(layer "F.Fab")
			(hide yes)
			(effects
				(font
					(size 1.016 1.016)
					(thickness 0.1524)
				)
			)
		)
		(duplicate_pad_numbers_are_jumpers no)
		(fp_line
			(start 0.635 0)
			(end -0.635 0)
			(stroke
				(width 0.508)
				(type default)
			)
			(layer "F.SilkS")
		)
		(fp_rect
			(start -0.9652 1.778)
			(end 0.9652 -1.778)
			(stroke
				(width 0)
				(type default)
			)
			(fill no)
			(layer "F.CrtYd")
		)
		(fp_poly
			(pts
				(xy -0.9652 -1.778) (xy 0.9652 -1.778) (xy 0.9652 1.778) (xy -0.9652 1.778)
			)
			(stroke
				(width 0)
				(type default)
			)
			(fill no)
			(layer "F.Fab")
		)
		(pad "1" smd rect
			(at 0 -0.9652 270)
			(size 1.397 1.143)
			(layers "F.Cu" "F.Mask" "F.Paste")
			(net "P5V_USB")
		)
		(pad "2" smd rect
			(at 0 0.9652 270)
			(size 1.397 1.143)
			(layers "F.Cu" "F.Mask" "F.Paste")
			(net "GND")
		)
	)
)
